# T6G (Grand Teton) — schematic netlist excerpt (pin names and nets, part order shuffled) for the footprints in the layout excerpt that follows; sources: Cadence DE-HDL packaged netlist, KiCad conversion of 04192023_DAF0TMB3IC0_F0TG_MB_C_brd_V02_OCP.brd

R1278  Q_RES  33 5% CHIP  pkg 0402LF  page 81 : A = FM_P1_PCC0_N ; B = FM_P1_PCC0_R_N
R8420  Q_RES  1K 1% CHIP  pkg 0402LF  page 131 : A = SGPIO_OCP_SFF_LD_N ; B = P3V3_OCP_SFF
C791  Q_CAP  0.1UF 10V 10% X7S  pkg C0201  page 301 : A = P0V9_CPU0_RT2_2A_2D ; B = GND

(kicad_pcb
	(version 20260206)
	(generator "pcbnew")
	(generator_version "10.0")
	(general
		(thickness 1.6)
		(legacy_teardrops no)
	)
	(paper "A4")
	(title_block
		(title "04192023_DAF0TMB3IC0_F0TG_MB_C_brd_V02_OCP.brd")
		(comment 1 "Grand Teton / footprints 6371-6373 of 8354")
	)
	(layers
		(0 "F.Cu" signal "TOP")
		(4 "In1.Cu" signal "GND")
		(6 "In2.Cu" signal "IN1")
		(8 "In3.Cu" signal "GND1")
		(10 "In4.Cu" signal "IN2")
		(12 "In5.Cu" signal "GND2")
		(14 "In6.Cu" signal "IN3")
		(16 "In7.Cu" signal "GND3")
		(18 "In8.Cu" signal "VCC")
		(20 "In9.Cu" signal "VCC1")
		(22 "In10.Cu" signal "GND4")
		(24 "In11.Cu" signal "IN4")
		(26 "In12.Cu" signal "GND5")
		(28 "In13.Cu" signal "IN5")
		(30 "In14.Cu" signal "GND6")
		(32 "In15.Cu" signal "IN6")
		(34 "In16.Cu" signal "GND7")
		(2 "B.Cu" signal "BOTTOM")
		(9 "F.Adhes" user "F.Adhesive")
		(11 "B.Adhes" user "B.Adhesive")
		(13 "F.Paste" user "Package Geometry/Pastemask Top")
		(15 "B.Paste" user "Package Geometry/Pastemask Bottom")
		(5 "F.SilkS" user "Ref Des/Silkscreen Top")
		(7 "B.SilkS" user "Ref Des/Silkscreen Bottom")
		(1 "F.Mask" user "Board Geometry/Soldermask Top")
		(3 "B.Mask" user "Board Geometry/Soldermask Bottom")
		(17 "Dwgs.User" user "User.Drawings")
		(19 "Cmts.User" user "User.Comments")
		(21 "Eco1.User" user "User.Eco1")
		(23 "Eco2.User" user "User.Eco2")
		(25 "Edge.Cuts" user "Board Geometry/Outline")
		(27 "Margin" user)
		(31 "F.CrtYd" user "Package Geometry/Place Bound Top")
		(29 "B.CrtYd" user "Package Geometry/Place Bound Bottom")
		(35 "F.Fab" user "Ref Des/Assembly Top")
		(33 "B.Fab" user "Ref Des/Assembly Bottom")
	)
	(footprint ""
		(layer "B.Cu")
		(at 452.62546 -10.60577 90)
		(property "Reference" "R8420"
			(at 0 0 90)
			(layer "B.SilkS")
			(hide yes)
			(effects
				(font
					(size 1.27 1.27)
				)
				(justify mirror)
			)
		)
		(property "Value" ""
			(at 0 0 90)
			(layer "B.Fab")
			(effects
				(font
					(size 1.27 1.27)
				)
				(justify mirror)
			)
		)
		(duplicate_pad_numbers_are_jumpers no)
		(fp_line
			(start 0.7874 -0.4064)
			(end -0.7874 -0.4064)
			(stroke
				(width 0.1524)
				(type default)
			)
			(layer "B.SilkS")
		)
		(fp_line
			(start -0.7874 -0.4064)
			(end -0.7874 0.4064)
			(stroke
				(width 0.1524)
				(type default)
			)
			(layer "B.SilkS")
		)
		(fp_line
			(start 0.7874 0.4064)
			(end 0.7874 -0.4064)
			(stroke
				(width 0.1524)
				(type default)
			)
			(layer "B.SilkS")
		)
		(fp_line
			(start -0.7874 0.4064)
			(end 0.7874 0.4064)
			(stroke
				(width 0.1524)
				(type default)
			)
			(layer "B.SilkS")
		)
		(fp_line
			(start 0.67945 -0.305054)
			(end 0.12065 -0.305054)
			(stroke
				(width 0.1)
				(type default)
			)
			(layer "B.Fab")
		)
		(fp_line
			(start 0.12065 -0.305054)
			(end 0.12065 -0.2794)
			(stroke
				(width 0.1)
				(type default)
			)
			(layer "B.Fab")
		)
		(fp_line
			(start -0.12065 -0.3048)
			(end -0.67945 -0.3048)
			(stroke
				(width 0.1)
				(type default)
			)
			(layer "B.Fab")
		)
		(fp_line
			(start -0.67945 -0.3048)
			(end -0.67945 0.3048)
			(stroke
				(width 0.1)
				(type default)
			)
			(layer "B.Fab")
		)
		(fp_line
			(start 0.12065 -0.2794)
			(end -0.12065 -0.2794)
			(stroke
				(width 0.1)
				(type default)
			)
			(layer "B.Fab")
		)
		(fp_line
			(start -0.12065 -0.2794)
			(end -0.12065 -0.3048)
			(stroke
				(width 0.1)
				(type default)
			)
			(layer "B.Fab")
		)
		(fp_line
			(start 0.12065 0.2794)
			(end 0.12065 0.3048)
			(stroke
				(width 0.1)
				(type default)
			)
			(layer "B.Fab")
		)
		(fp_line
			(start -0.120396 0.2794)
			(end 0.12065 0.2794)
			(stroke
				(width 0.1)
				(type default)
			)
			(layer "B.Fab")
		)
		(fp_line
			(start 0.67945 0.3048)
			(end 0.67945 -0.305054)
			(stroke
				(width 0.1)
				(type default)
			)
			(layer "B.Fab")
		)
		(fp_line
			(start 0.12065 0.3048)
			(end 0.67945 0.3048)
			(stroke
				(width 0.1)
				(type default)
			)
			(layer "B.Fab")
		)
		(fp_line
			(start -0.120396 0.3048)
			(end -0.120396 0.2794)
			(stroke
				(width 0.1)
				(type default)
			)
			(layer "B.Fab")
		)
		(fp_line
			(start -0.67945 0.3048)
			(end -0.120396 0.3048)
			(stroke
				(width 0.1)
				(type default)
			)
			(layer "B.Fab")
		)
		(pad "1" smd circle
			(at 0.40005 0 270)
			(size 0 0)
			(layers "B.Cu" "B.Mask" "B.Paste")
			(net "SGPIO_OCP_SFF_LD_N")
		)
		(pad "2" smd circle
			(at -0.40005 0 270)
			(size 0 0)
			(layers "B.Cu" "B.Mask" "B.Paste")
			(net "P3V3_OCP_SFF")
		)
	)
	(footprint ""
		(layer "B.Cu")
		(at 183.045608 -126.833376 90)
		(property "Reference" "R1278"
			(at 0 0 90)
			(layer "B.SilkS")
			(hide yes)
			(effects
				(font
					(size 1.27 1.27)
				)
				(justify mirror)
			)
		)
		(property "Value" ""
			(at 0 0 90)
			(layer "B.Fab")
			(effects
				(font
					(size 1.27 1.27)
				)
				(justify mirror)
			)
		)
		(duplicate_pad_numbers_are_jumpers no)
		(fp_line
			(start 0.7874 -0.4064)
			(end -0.7874 -0.4064)
			(stroke
				(width 0.1524)
				(type default)
			)
			(layer "B.SilkS")
		)
		(fp_line
			(start -0.7874 -0.4064)
			(end -0.7874 0.4064)
			(stroke
				(width 0.1524)
				(type default)
			)
			(layer "B.SilkS")
		)
		(fp_line
			(start 0.7874 0.4064)
			(end 0.7874 -0.4064)
			(stroke
				(width 0.1524)
				(type default)
			)
			(layer "B.SilkS")
		)
		(fp_line
			(start -0.7874 0.4064)
			(end 0.7874 0.4064)
			(stroke
				(width 0.1524)
				(type default)
			)
			(layer "B.SilkS")
		)
		(fp_line
			(start 0.67945 -0.305054)
			(end 0.12065 -0.305054)
			(stroke
				(width 0.1)
				(type default)
			)
			(layer "B.Fab")
		)
		(fp_line
			(start 0.12065 -0.305054)
			(end 0.12065 -0.2794)
			(stroke
				(width 0.1)
				(type default)
			)
			(layer "B.Fab")
		)
		(fp_line
			(start -0.12065 -0.3048)
			(end -0.67945 -0.3048)
			(stroke
				(width 0.1)
				(type default)
			)
			(layer "B.Fab")
		)
		(fp_line
			(start -0.67945 -0.3048)
			(end -0.67945 0.3048)
			(stroke
				(width 0.1)
				(type default)
			)
			(layer "B.Fab")
		)
		(fp_line
			(start 0.12065 -0.2794)
			(end -0.12065 -0.2794)
			(stroke
				(width 0.1)
				(type default)
			)
			(layer "B.Fab")
		)
		(fp_line
			(start -0.12065 -0.2794)
			(end -0.12065 -0.3048)
			(stroke
				(width 0.1)
				(type default)
			)
			(layer "B.Fab")
		)
		(fp_line
			(start 0.12065 0.2794)
			(end 0.12065 0.3048)
			(stroke
				(width 0.1)
				(type default)
			)
			(layer "B.Fab")
		)
		(fp_line
			(start -0.120396 0.2794)
			(end 0.12065 0.2794)
			(stroke
				(width 0.1)
				(type default)
			)
			(layer "B.Fab")
		)
		(fp_line
			(start 0.67945 0.3048)
			(end 0.67945 -0.305054)
			(stroke
				(width 0.1)
				(type default)
			)
			(layer "B.Fab")
		)
		(fp_line
			(start 0.12065 0.3048)
			(end 0.67945 0.3048)
			(stroke
				(width 0.1)
				(type default)
			)
			(layer "B.Fab")
		)
		(fp_line
			(start -0.120396 0.3048)
			(end -0.120396 0.2794)
			(stroke
				(width 0.1)
				(type default)
			)
			(layer "B.Fab")
		)
		(fp_line
			(start -0.67945 0.3048)
			(end -0.120396 0.3048)
			(stroke
				(width 0.1)
				(type default)
			)
			(layer "B.Fab")
		)
		(pad "1" smd circle
			(at 0.40005 0 270)
			(size 0 0)
			(layers "B.Cu" "B.Mask" "B.Paste")
			(net "FM_P1_PCC0_N")
		)
		(pad "2" smd circle
			(at -0.40005 0 270)
			(size 0 0)
			(layers "B.Cu" "B.Mask" "B.Paste")
			(net "FM_P1_PCC0_R_N")
		)
	)
	(footprint ""
		(layer "B.Cu")
		(at 407.946098 -396.393162 -90)
		(property "Reference" "C791"
			(at 0 0 90)
			(layer "B.SilkS")
			(hide yes)
			(effects
				(font
					(size 1.27 1.27)
				)
				(justify mirror)
			)
		)
		(property "Value" ""
			(at 0 0 90)
			(layer "B.Fab")
			(effects
				(font
					(size 1.27 1.27)
				)
				(justify mirror)
			)
		)
		(duplicate_pad_numbers_are_jumpers no)
		(fp_line
			(start -0.299974 0.150114)
			(end 0.299974 0.150114)
			(stroke
				(width 0.1)
				(type default)
			)
			(layer "B.Fab")
		)
		(fp_line
			(start 0.299974 0.150114)
			(end 0.299974 -0.150114)
			(stroke
				(width 0.1)
				(type default)
			)
			(layer "B.Fab")
		)
		(fp_line
			(start -0.299974 -0.150114)
			(end -0.299974 0.150114)
			(stroke
				(width 0.1)
				(type default)
			)
			(layer "B.Fab")
		)
		(fp_line
			(start 0.299974 -0.150114)
			(end -0.299974 -0.150114)
			(stroke
				(width 0.1)
				(type default)
			)
			(layer "B.Fab")
		)
		(pad "1" smd rect
			(at 0.2667 0 90)
			(size 0.3048 0.381)
			(layers "B.Cu" "B.Mask" "B.Paste")
			(net "P0V9_CPU0_RT2_2A_2D")
		)
		(pad "2" smd rect
			(at -0.2667 0 90)
			(size 0.3048 0.381)
			(layers "B.Cu" "B.Mask" "B.Paste")
			(net "GND")
		)
	)
)
